# SCM (Grand Teton) — schematic netlist excerpt (pin names and nets, part order shuffled) for the footprints in the layout excerpt that follows; sources: Cadence DE-HDL packaged netlist, KiCad conversion of 12092022_DA0F0TMDCD0_F0T_Management_Board_D_brd_V3_OCP.brd

R253  Q_RES  2.2K 5% CHIP  pkg 0402LF  page 27 : A = P3V3_AUX ; B = SMB_BMC_MM5_R_SDA
R256  Q_RES  2.2K 5% CHIP  pkg 0402LF  page 27 : A = P3V3_AUX ; B = SMB_BMC_MM7_R_SCL

(kicad_pcb
	(version 20260206)
	(generator "pcbnew")
	(generator_version "10.0")
	(general
		(thickness 1.6)
		(legacy_teardrops no)
	)
	(paper "A4")
	(title_block
		(title "12092022_DA0F0TMDCD0_F0T_Management_Board_D_brd_V3_OCP.brd")
		(comment 1 "Grand Teton / footprints 1119-1120 of 1440")
	)
	(layers
		(0 "F.Cu" signal "TOP")
		(4 "In1.Cu" signal "GND")
		(6 "In2.Cu" signal "IN1")
		(8 "In3.Cu" signal "GND1")
		(10 "In4.Cu" signal "IN2")
		(12 "In5.Cu" signal "VCC")
		(14 "In6.Cu" signal "VCC1")
		(16 "In7.Cu" signal "IN3")
		(18 "In8.Cu" signal "GND2")
		(20 "In9.Cu" signal "IN4")
		(22 "In10.Cu" signal "GND3")
		(2 "B.Cu" signal "BOTTOM")
		(9 "F.Adhes" user "F.Adhesive")
		(11 "B.Adhes" user "B.Adhesive")
		(13 "F.Paste" user "Package Geometry/Pastemask Top")
		(15 "B.Paste" user "Package Geometry/Pastemask Bottom")
		(5 "F.SilkS" user "Ref Des/Silkscreen Top")
		(7 "B.SilkS" user "Ref Des/Silkscreen Bottom")
		(1 "F.Mask" user "Board Geometry/Soldermask Top")
		(3 "B.Mask" user "Board Geometry/Soldermask Bottom")
		(17 "Dwgs.User" user "User.Drawings")
		(19 "Cmts.User" user "User.Comments")
		(21 "Eco1.User" user "User.Eco1")
		(23 "Eco2.User" user "User.Eco2")
		(25 "Edge.Cuts" user "Board Geometry/Outline")
		(27 "Margin" user)
		(31 "F.CrtYd" user "Package Geometry/Place Bound Top")
		(29 "B.CrtYd" user "Package Geometry/Place Bound Bottom")
		(35 "F.Fab" user "Ref Des/Assembly Top")
		(33 "B.Fab" user "Ref Des/Assembly Bottom")
	)
	(footprint ""
		(layer "B.Cu")
		(at 63.014098 -28.356306 -90)
		(property "Reference" "R256"
			(at 0 0 90)
			(layer "B.SilkS")
			(hide yes)
			(effects
				(font
					(size 1.27 1.27)
				)
				(justify mirror)
			)
		)
		(property "Value" ""
			(at 0 0 90)
			(layer "B.Fab")
			(effects
				(font
					(size 1.27 1.27)
				)
				(justify mirror)
			)
		)
		(duplicate_pad_numbers_are_jumpers no)
		(fp_line
			(start -0.7874 0.4064)
			(end 0.7874 0.4064)
			(stroke
				(width 0.1524)
				(type default)
			)
			(layer "B.SilkS")
		)
		(fp_line
			(start 0.7874 0.4064)
			(end 0.7874 -0.4064)
			(stroke
				(width 0.1524)
				(type default)
			)
			(layer "B.SilkS")
		)
		(fp_line
			(start -0.7874 -0.4064)
			(end -0.7874 0.4064)
			(stroke
				(width 0.1524)
				(type default)
			)
			(layer "B.SilkS")
		)
		(fp_line
			(start 0.7874 -0.4064)
			(end -0.7874 -0.4064)
			(stroke
				(width 0.1524)
				(type default)
			)
			(layer "B.SilkS")
		)
		(fp_line
			(start -0.67945 0.3048)
			(end -0.120396 0.3048)
			(stroke
				(width 0.1)
				(type default)
			)
			(layer "B.Fab")
		)
		(fp_line
			(start -0.120396 0.3048)
			(end -0.120396 0.2794)
			(stroke
				(width 0.1)
				(type default)
			)
			(layer "B.Fab")
		)
		(fp_line
			(start 0.12065 0.3048)
			(end 0.67945 0.3048)
			(stroke
				(width 0.1)
				(type default)
			)
			(layer "B.Fab")
		)
		(fp_line
			(start 0.67945 0.3048)
			(end 0.67945 -0.305054)
			(stroke
				(width 0.1)
				(type default)
			)
			(layer "B.Fab")
		)
		(fp_line
			(start -0.120396 0.2794)
			(end 0.12065 0.2794)
			(stroke
				(width 0.1)
				(type default)
			)
			(layer "B.Fab")
		)
		(fp_line
			(start 0.12065 0.2794)
			(end 0.12065 0.3048)
			(stroke
				(width 0.1)
				(type default)
			)
			(layer "B.Fab")
		)
		(fp_line
			(start -0.12065 -0.2794)
			(end -0.12065 -0.3048)
			(stroke
				(width 0.1)
				(type default)
			)
			(layer "B.Fab")
		)
		(fp_line
			(start 0.12065 -0.2794)
			(end -0.12065 -0.2794)
			(stroke
				(width 0.1)
				(type default)
			)
			(layer "B.Fab")
		)
		(fp_line
			(start -0.67945 -0.3048)
			(end -0.67945 0.3048)
			(stroke
				(width 0.1)
				(type default)
			)
			(layer "B.Fab")
		)
		(fp_line
			(start -0.12065 -0.3048)
			(end -0.67945 -0.3048)
			(stroke
				(width 0.1)
				(type default)
			)
			(layer "B.Fab")
		)
		(fp_line
			(start 0.12065 -0.305054)
			(end 0.12065 -0.2794)
			(stroke
				(width 0.1)
				(type default)
			)
			(layer "B.Fab")
		)
		(fp_line
			(start 0.67945 -0.305054)
			(end 0.12065 -0.305054)
			(stroke
				(width 0.1)
				(type default)
			)
			(layer "B.Fab")
		)
		(pad "1" smd circle
			(at 0.40005 0 90)
			(size 0 0)
			(layers "B.Cu" "B.Mask" "B.Paste")
			(net "P3V3_AUX")
		)
		(pad "2" smd circle
			(at -0.40005 0 90)
			(size 0 0)
			(layers "B.Cu" "B.Mask" "B.Paste")
			(net "SMB_BMC_MM7_R_SCL")
		)
	)
	(footprint ""
		(layer "B.Cu")
		(at 60.452 -27.87904)
		(property "Reference" "R253"
			(at 0 0 0)
			(layer "B.SilkS")
			(hide yes)
			(effects
				(font
					(size 1.27 1.27)
				)
				(justify mirror)
			)
		)
		(property "Value" ""
			(at 0 0 0)
			(layer "B.Fab")
			(effects
				(font
					(size 1.27 1.27)
				)
				(justify mirror)
			)
		)
		(duplicate_pad_numbers_are_jumpers no)
		(fp_line
			(start -0.7874 -0.4064)
			(end -0.7874 0.4064)
			(stroke
				(width 0.1524)
				(type default)
			)
			(layer "B.SilkS")
		)
		(fp_line
			(start -0.7874 0.4064)
			(end 0.7874 0.4064)
			(stroke
				(width 0.1524)
				(type default)
			)
			(layer "B.SilkS")
		)
		(fp_line
			(start 0.7874 -0.4064)
			(end -0.7874 -0.4064)
			(stroke
				(width 0.1524)
				(type default)
			)
			(layer "B.SilkS")
		)
		(fp_line
			(start 0.7874 0.4064)
			(end 0.7874 -0.4064)
			(stroke
				(width 0.1524)
				(type default)
			)
			(layer "B.SilkS")
		)
		(fp_line
			(start -0.67945 -0.3048)
			(end -0.67945 0.3048)
			(stroke
				(width 0.1)
				(type default)
			)
			(layer "B.Fab")
		)
		(fp_line
			(start -0.67945 0.3048)
			(end -0.120396 0.3048)
			(stroke
				(width 0.1)
				(type default)
			)
			(layer "B.Fab")
		)
		(fp_line
			(start -0.12065 -0.3048)
			(end -0.67945 -0.3048)
			(stroke
				(width 0.1)
				(type default)
			)
			(layer "B.Fab")
		)
		(fp_line
			(start -0.12065 -0.2794)
			(end -0.12065 -0.3048)
			(stroke
				(width 0.1)
				(type default)
			)
			(layer "B.Fab")
		)
		(fp_line
			(start -0.120396 0.2794)
			(end 0.12065 0.2794)
			(stroke
				(width 0.1)
				(type default)
			)
			(layer "B.Fab")
		)
		(fp_line
			(start -0.120396 0.3048)
			(end -0.120396 0.2794)
			(stroke
				(width 0.1)
				(type default)
			)
			(layer "B.Fab")
		)
		(fp_line
			(start 0.12065 -0.305054)
			(end 0.12065 -0.2794)
			(stroke
				(width 0.1)
				(type default)
			)
			(layer "B.Fab")
		)
		(fp_line
			(start 0.12065 -0.2794)
			(end -0.12065 -0.2794)
			(stroke
				(width 0.1)
				(type default)
			)
			(layer "B.Fab")
		)
		(fp_line
			(start 0.12065 0.2794)
			(end 0.12065 0.3048)
			(stroke
				(width 0.1)
				(type default)
			)
			(layer "B.Fab")
		)
		(fp_line
			(start 0.12065 0.3048)
			(end 0.67945 0.3048)
			(stroke
				(width 0.1)
				(type default)
			)
			(layer "B.Fab")
		)
		(fp_line
			(start 0.67945 -0.305054)
			(end 0.12065 -0.305054)
			(stroke
				(width 0.1)
				(type default)
			)
			(layer "B.Fab")
		)
		(fp_line
			(start 0.67945 0.3048)
			(end 0.67945 -0.305054)
			(stroke
				(width 0.1)
				(type default)
			)
			(layer "B.Fab")
		)
		(pad "1" smd circle
			(at 0.40005 0 180)
			(size 0 0)
			(layers "B.Cu" "B.Mask" "B.Paste")
			(net "P3V3_AUX")
		)
		(pad "2" smd circle
			(at -0.40005 0 180)
			(size 0 0)
			(layers "B.Cu" "B.Mask" "B.Paste")
			(net "SMB_BMC_MM5_R_SDA")
		)
	)
)
